FILE_TYPE = CONNECTIVITY;
{Allegro Design Entry HDL 16.6-p007 (v16-6-112F) 10/10/2012}
"PAGE_NUMBER" = 33;
0"NC";
1"UPI_CPU0_CPU1_P0P0_DN<19..0>";
2"UPI_CPU0_CPU1_P0P0_DP<19..0>";
3"UPI_CPU1_CPU0_P0P0_DN<19..0>";
4"UPI_CPU1_CPU0_P0P0_DP<19..0>";
5"UPI_CPU0_CPU1_P0P0_DP<7>";
6"UPI_CPU1_CPU0_P0P0_DP<14>";
7"UPI_CPU1_CPU0_P0P0_DP<12>";
8"UPI_CPU1_CPU0_P0P0_DP<9>";
9"UPI_CPU1_CPU0_P0P0_DP<10>";
10"UPI_CPU1_CPU0_P0P0_DP<13>";
11"UPI_CPU1_CPU0_P0P0_DN<19>";
12"UPI_CPU1_CPU0_P0P0_DN<18>";
13"UPI_CPU1_CPU0_P0P0_DN<17>";
14"UPI_CPU1_CPU0_P0P0_DN<16>";
15"UPI_CPU1_CPU0_P0P0_DN<15>";
16"UPI_CPU1_CPU0_P0P0_DN<14>";
17"UPI_CPU1_CPU0_P0P0_DN<13>";
18"UPI_CPU1_CPU0_P0P0_DN<12>";
19"UPI_CPU1_CPU0_P0P0_DN<11>";
20"UPI_CPU1_CPU0_P0P0_DP<19>";
21"UPI_CPU1_CPU0_P0P0_DP<18>";
22"UPI_CPU1_CPU0_P0P0_DP<17>";
23"UPI_CPU1_CPU0_P0P0_DP<16>";
24"UPI_CPU1_CPU0_P0P0_DP<15>";
25"UPI_CPU1_CPU0_P0P0_DP<11>";
26"UPI_CPU1_CPU0_P0P0_DP<8>";
27"UPI_CPU1_CPU0_P0P0_DP<7>";
28"UPI_CPU1_CPU0_P0P0_DP<6>";
29"UPI_CPU1_CPU0_P0P0_DP<5>";
30"UPI_CPU1_CPU0_P0P0_DP<4>";
31"UPI_CPU1_CPU0_P0P0_DP<3>";
32"UPI_CPU1_CPU0_P0P0_DP<2>";
33"UPI_CPU1_CPU0_P0P0_DP<1>";
34"UPI_CPU1_CPU0_P0P0_DP<0>";
35"UPI_CPU1_CPU0_P0P0_DN<10>";
36"UPI_CPU1_CPU0_P0P0_DN<9>";
37"UPI_CPU1_CPU0_P0P0_DN<8>";
38"UPI_CPU1_CPU0_P0P0_DN<7>";
39"UPI_CPU1_CPU0_P0P0_DN<6>";
40"UPI_CPU1_CPU0_P0P0_DN<5>";
41"UPI_CPU1_CPU0_P0P0_DN<4>";
42"UPI_CPU1_CPU0_P0P0_DN<3>";
43"UPI_CPU1_CPU0_P0P0_DN<2>";
44"UPI_CPU1_CPU0_P0P0_DN<1>";
45"UPI_CPU1_CPU0_P0P0_DN<0>";
46"UPI_CPU0_CPU1_P0P0_DN<19>";
47"UPI_CPU0_CPU1_P0P0_DN<18>";
48"UPI_CPU0_CPU1_P0P0_DN<17>";
49"UPI_CPU0_CPU1_P0P0_DN<16>";
50"UPI_CPU0_CPU1_P0P0_DN<15>";
51"UPI_CPU0_CPU1_P0P0_DN<14>";
52"UPI_CPU0_CPU1_P0P0_DN<13>";
53"UPI_CPU0_CPU1_P0P0_DN<12>";
54"UPI_CPU0_CPU1_P0P0_DN<11>";
55"UPI_CPU0_CPU1_P0P0_DP<19>";
56"UPI_CPU0_CPU1_P0P0_DP<18>";
57"UPI_CPU0_CPU1_P0P0_DP<17>";
58"UPI_CPU0_CPU1_P0P0_DP<16>";
59"UPI_CPU0_CPU1_P0P0_DP<15>";
60"UPI_CPU0_CPU1_P0P0_DP<14>";
61"UPI_CPU0_CPU1_P0P0_DP<13>";
62"UPI_CPU0_CPU1_P0P0_DP<12>";
63"UPI_CPU0_CPU1_P0P0_DP<11>";
64"UPI_CPU0_CPU1_P0P0_DP<10>";
65"UPI_CPU0_CPU1_P0P0_DP<9>";
66"UPI_CPU0_CPU1_P0P0_DP<8>";
67"UPI_CPU0_CPU1_P0P0_DP<6>";
68"UPI_CPU0_CPU1_P0P0_DP<5>";
69"UPI_CPU0_CPU1_P0P0_DP<4>";
70"UPI_CPU0_CPU1_P0P0_DP<3>";
71"UPI_CPU0_CPU1_P0P0_DP<2>";
72"UPI_CPU0_CPU1_P0P0_DP<1>";
73"UPI_CPU0_CPU1_P0P0_DP<0>";
74"UPI_CPU0_CPU1_P0P0_DN<10>";
75"UPI_CPU0_CPU1_P0P0_DN<9>";
76"UPI_CPU0_CPU1_P0P0_DN<8>";
77"UPI_CPU0_CPU1_P0P0_DN<7>";
78"UPI_CPU0_CPU1_P0P0_DN<6>";
79"UPI_CPU0_CPU1_P0P0_DN<5>";
80"UPI_CPU0_CPU1_P0P0_DN<4>";
81"UPI_CPU0_CPU1_P0P0_DN<3>";
82"UPI_CPU0_CPU1_P0P0_DN<2>";
83"UPI_CPU0_CPU1_P0P0_DN<1>";
84"UPI_CPU0_CPU1_P0P0_DN<0>";
%"TAP"
"1","(-5250,1900)","2","mstr_standard","I10";
;
CDS_LIB"mstr_standard"
BODY_TYPE"PLUMBING"
HDL_TAP"TRUE";
"B \NAC \NWC"3;
"S \NAC"
BN"13"17;
%"TAP"
"1","(-5250,2000)","2","mstr_standard","I11";
;
CDS_LIB"mstr_standard"
BODY_TYPE"PLUMBING"
HDL_TAP"TRUE";
"B \NAC \NWC"3;
"S \NAC"
BN"11"19;
%"TAP"
"1","(-5250,2100)","2","mstr_standard","I13";
;
CDS_LIB"mstr_standard"
BODY_TYPE"PLUMBING"
HDL_TAP"TRUE";
"B \NAC \NWC"3;
"S \NAC"
BN"9"36;
%"TAP"
"1","(-5250,2050)","2","mstr_standard","I14";
;
CDS_LIB"mstr_standard"
BODY_TYPE"PLUMBING"
HDL_TAP"TRUE";
"B \NAC \NWC"3;
"S \NAC"
BN"10"35;
%"TAP"
"1","(-5250,2250)","2","mstr_standard","I15";
;
CDS_LIB"mstr_standard"
BODY_TYPE"PLUMBING"
HDL_TAP"TRUE";
"B \NAC \NWC"3;
"S \NAC"
BN"6"39;
%"TAP"
"1","(-5250,2200)","2","mstr_standard","I16";
;
CDS_LIB"mstr_standard"
BODY_TYPE"PLUMBING"
HDL_TAP"TRUE";
"B \NAC \NWC"3;
"S \NAC"
BN"7"38;
%"TAP"
"1","(-5250,2150)","2","mstr_standard","I17";
;
CDS_LIB"mstr_standard"
BODY_TYPE"PLUMBING"
HDL_TAP"TRUE";
"B \NAC \NWC"3;
"S \NAC"
BN"8"37;
%"TAP"
"1","(-5250,2350)","2","mstr_standard","I18";
;
CDS_LIB"mstr_standard"
BODY_TYPE"PLUMBING"
HDL_TAP"TRUE";
"B \NAC \NWC"3;
"S \NAC"
BN"4"41;
%"TAP"
"1","(-5250,2300)","2","mstr_standard","I19";
;
CDS_LIB"mstr_standard"
BODY_TYPE"PLUMBING"
HDL_TAP"TRUE";
"B \NAC \NWC"3;
"S \NAC"
BN"5"40;
%"TAP"
"1","(-5250,2500)","2","mstr_standard","I20";
;
CDS_LIB"mstr_standard"
BODY_TYPE"PLUMBING"
HDL_TAP"TRUE";
"B \NAC \NWC"3;
"S \NAC"
BN"1"44;
%"TAP"
"1","(-5250,2450)","2","mstr_standard","I21";
;
CDS_LIB"mstr_standard"
BODY_TYPE"PLUMBING"
HDL_TAP"TRUE";
"B \NAC \NWC"3;
"S \NAC"
BN"2"43;
%"TAP"
"1","(-5250,2400)","2","mstr_standard","I22";
;
CDS_LIB"mstr_standard"
BODY_TYPE"PLUMBING"
HDL_TAP"TRUE";
"B \NAC \NWC"3;
"S \NAC"
BN"3"42;
%"TAP"
"1","(-5250,2750)","2","mstr_standard","I23";
;
CDS_LIB"mstr_standard"
BODY_TYPE"PLUMBING"
HDL_TAP"TRUE";
"B \NAC \NWC"4;
"S \NAC"
BN"17"22;
%"TAP"
"1","(-5250,2650)","2","mstr_standard","I24";
;
CDS_LIB"mstr_standard"
BODY_TYPE"PLUMBING"
HDL_TAP"TRUE";
"B \NAC \NWC"4;
"S \NAC"
BN"19"20;
%"TAP"
"1","(-5250,2700)","2","mstr_standard","I25";
;
CDS_LIB"mstr_standard"
BODY_TYPE"PLUMBING"
HDL_TAP"TRUE";
"B \NAC \NWC"4;
"S \NAC"
BN"18"21;
%"TAP"
"1","(-5250,2550)","2","mstr_standard","I26";
;
CDS_LIB"mstr_standard"
BODY_TYPE"PLUMBING"
HDL_TAP"TRUE";
"B \NAC \NWC"3;
"S \NAC"
BN"0"45;
%"TAP"
"1","(-5250,2850)","2","mstr_standard","I27";
;
CDS_LIB"mstr_standard"
BODY_TYPE"PLUMBING"
HDL_TAP"TRUE";
"B \NAC \NWC"4;
"S \NAC"
BN"15"24;
%"TAP"
"1","(-5250,2800)","2","mstr_standard","I28";
;
CDS_LIB"mstr_standard"
BODY_TYPE"PLUMBING"
HDL_TAP"TRUE";
"B \NAC \NWC"4;
"S \NAC"
BN"16"23;
%"TAP"
"1","(-5250,2950)","2","mstr_standard","I29";
;
CDS_LIB"mstr_standard"
BODY_TYPE"PLUMBING"
HDL_TAP"TRUE";
"B \NAC \NWC"4;
"S \NAC"
BN"13"10;
%"TAP"
"1","(-5250,1600)","2","mstr_standard","I3";
;
CDS_LIB"mstr_standard"
BODY_TYPE"PLUMBING"
HDL_TAP"TRUE";
"B \NAC \NWC"3;
"S \NAC"
BN"19"11;
%"TAP"
"1","(-5250,3000)","2","mstr_standard","I30";
;
CDS_LIB"mstr_standard"
BODY_TYPE"PLUMBING"
HDL_TAP"TRUE";
"B \NAC \NWC"4;
"S \NAC"
BN"12"7;
%"TAP"
"1","(-5250,2900)","2","mstr_standard","I31";
;
CDS_LIB"mstr_standard"
BODY_TYPE"PLUMBING"
HDL_TAP"TRUE";
"B \NAC \NWC"4;
"S \NAC"
BN"14"6;
%"TAP"
"1","(-5250,3050)","2","mstr_standard","I32";
;
CDS_LIB"mstr_standard"
BODY_TYPE"PLUMBING"
HDL_TAP"TRUE";
"B \NAC \NWC"4;
"S \NAC"
BN"11"25;
%"TAP"
"1","(-5250,3100)","2","mstr_standard","I33";
;
CDS_LIB"mstr_standard"
BODY_TYPE"PLUMBING"
HDL_TAP"TRUE";
"B \NAC \NWC"4;
"S \NAC"
BN"10"9;
%"TAP"
"1","(-5250,3150)","2","mstr_standard","I34";
;
CDS_LIB"mstr_standard"
BODY_TYPE"PLUMBING"
HDL_TAP"TRUE";
"B \NAC \NWC"4;
"S \NAC"
BN"9"8;
%"TAP"
"1","(-5250,3250)","2","mstr_standard","I35";
;
CDS_LIB"mstr_standard"
BODY_TYPE"PLUMBING"
HDL_TAP"TRUE";
"B \NAC \NWC"4;
"S \NAC"
BN"7"27;
%"TAP"
"1","(-5250,3200)","2","mstr_standard","I36";
;
CDS_LIB"mstr_standard"
BODY_TYPE"PLUMBING"
HDL_TAP"TRUE";
"B \NAC \NWC"4;
"S \NAC"
BN"8"26;
%"TAP"
"1","(-5250,3300)","2","mstr_standard","I37";
;
CDS_LIB"mstr_standard"
BODY_TYPE"PLUMBING"
HDL_TAP"TRUE";
"B \NAC \NWC"4;
"S \NAC"
BN"6"28;
%"TAP"
"1","(-5250,3400)","2","mstr_standard","I38";
;
CDS_LIB"mstr_standard"
BODY_TYPE"PLUMBING"
HDL_TAP"TRUE";
"B \NAC \NWC"4;
"S \NAC"
BN"4"30;
%"TAP"
"1","(-5250,3350)","2","mstr_standard","I39";
;
CDS_LIB"mstr_standard"
BODY_TYPE"PLUMBING"
HDL_TAP"TRUE";
"B \NAC \NWC"4;
"S \NAC"
BN"5"29;
%"TAP"
"1","(-5250,1700)","2","mstr_standard","I4";
;
CDS_LIB"mstr_standard"
BODY_TYPE"PLUMBING"
HDL_TAP"TRUE";
"B \NAC \NWC"3;
"S \NAC"
BN"17"13;
%"TAP"
"1","(-5250,3500)","2","mstr_standard","I40";
;
CDS_LIB"mstr_standard"
BODY_TYPE"PLUMBING"
HDL_TAP"TRUE";
"B \NAC \NWC"4;
"S \NAC"
BN"2"32;
%"TAP"
"1","(-5250,3450)","2","mstr_standard","I41";
;
CDS_LIB"mstr_standard"
BODY_TYPE"PLUMBING"
HDL_TAP"TRUE";
"B \NAC \NWC"4;
"S \NAC"
BN"3"31;
%"TAP"
"1","(-5250,3550)","2","mstr_standard","I42";
;
CDS_LIB"mstr_standard"
BODY_TYPE"PLUMBING"
HDL_TAP"TRUE";
"B \NAC \NWC"4;
"S \NAC"
BN"1"33;
%"TAP"
"1","(-5250,3600)","2","mstr_standard","I43";
;
CDS_LIB"mstr_standard"
BODY_TYPE"PLUMBING"
HDL_TAP"TRUE";
"B \NAC \NWC"4;
"S \NAC"
BN"0"34;
%"TAP"
"1","(-2925,1600)","0","mstr_standard","I44";
;
CDS_LIB"mstr_standard"
BODY_TYPE"PLUMBING"
HDL_TAP"TRUE";
"B \NAC \NWC"1;
"S \NAC"
BN"19"46;
%"TAP"
"1","(-2925,1750)","0","mstr_standard","I45";
;
CDS_LIB"mstr_standard"
BODY_TYPE"PLUMBING"
HDL_TAP"TRUE";
"B \NAC \NWC"1;
"S \NAC"
BN"16"49;
%"TAP"
"1","(-2925,1700)","0","mstr_standard","I46";
;
CDS_LIB"mstr_standard"
BODY_TYPE"PLUMBING"
HDL_TAP"TRUE";
"B \NAC \NWC"1;
"S \NAC"
BN"17"48;
%"TAP"
"1","(-2925,1650)","0","mstr_standard","I47";
;
CDS_LIB"mstr_standard"
BODY_TYPE"PLUMBING"
HDL_TAP"TRUE";
"B \NAC \NWC"1;
"S \NAC"
BN"18"47;
%"TAP"
"1","(-2925,1850)","0","mstr_standard","I48";
;
CDS_LIB"mstr_standard"
BODY_TYPE"PLUMBING"
HDL_TAP"TRUE";
"B \NAC \NWC"1;
"S \NAC"
BN"14"51;
%"TAP"
"1","(-2925,1800)","0","mstr_standard","I49";
;
CDS_LIB"mstr_standard"
BODY_TYPE"PLUMBING"
HDL_TAP"TRUE";
"B \NAC \NWC"1;
"S \NAC"
BN"15"50;
%"TAP"
"1","(-5250,1650)","2","mstr_standard","I5";
;
CDS_LIB"mstr_standard"
BODY_TYPE"PLUMBING"
HDL_TAP"TRUE";
"B \NAC \NWC"3;
"S \NAC"
BN"18"12;
%"TAP"
"1","(-2925,1900)","0","mstr_standard","I50";
;
CDS_LIB"mstr_standard"
BODY_TYPE"PLUMBING"
HDL_TAP"TRUE";
"B \NAC \NWC"1;
"S \NAC"
BN"13"52;
%"TAP"
"1","(-2925,2000)","0","mstr_standard","I51";
;
CDS_LIB"mstr_standard"
BODY_TYPE"PLUMBING"
HDL_TAP"TRUE";
"B \NAC \NWC"1;
"S \NAC"
BN"11"54;
%"TAP"
"1","(-2925,1950)","0","mstr_standard","I52";
;
CDS_LIB"mstr_standard"
BODY_TYPE"PLUMBING"
HDL_TAP"TRUE";
"B \NAC \NWC"1;
"S \NAC"
BN"12"53;
%"TAP"
"1","(-2925,2150)","0","mstr_standard","I53";
;
CDS_LIB"mstr_standard"
BODY_TYPE"PLUMBING"
HDL_TAP"TRUE";
"B \NAC \NWC"1;
"S \NAC"
BN"8"76;
%"TAP"
"1","(-2925,2100)","0","mstr_standard","I54";
;
CDS_LIB"mstr_standard"
BODY_TYPE"PLUMBING"
HDL_TAP"TRUE";
"B \NAC \NWC"1;
"S \NAC"
BN"9"75;
%"TAP"
"1","(-2925,2050)","0","mstr_standard","I55";
;
CDS_LIB"mstr_standard"
BODY_TYPE"PLUMBING"
HDL_TAP"TRUE";
"B \NAC \NWC"1;
"S \NAC"
BN"10"74;
%"TAP"
"1","(-2925,2250)","0","mstr_standard","I56";
;
CDS_LIB"mstr_standard"
BODY_TYPE"PLUMBING"
HDL_TAP"TRUE";
"B \NAC \NWC"1;
"S \NAC"
BN"6"78;
%"TAP"
"1","(-2925,2200)","0","mstr_standard","I57";
;
CDS_LIB"mstr_standard"
BODY_TYPE"PLUMBING"
HDL_TAP"TRUE";
"B \NAC \NWC"1;
"S \NAC"
BN"7"77;
%"TAP"
"1","(-2925,2300)","0","mstr_standard","I58";
;
CDS_LIB"mstr_standard"
BODY_TYPE"PLUMBING"
HDL_TAP"TRUE";
"B \NAC \NWC"1;
"S \NAC"
BN"5"79;
%"TAP"
"1","(-2925,2400)","0","mstr_standard","I59";
;
CDS_LIB"mstr_standard"
BODY_TYPE"PLUMBING"
HDL_TAP"TRUE";
"B \NAC \NWC"1;
"S \NAC"
BN"3"81;
%"TAP"
"1","(-5250,1750)","2","mstr_standard","I6";
;
CDS_LIB"mstr_standard"
BODY_TYPE"PLUMBING"
HDL_TAP"TRUE";
"B \NAC \NWC"3;
"S \NAC"
BN"16"14;
%"TAP"
"1","(-2925,2350)","0","mstr_standard","I60";
;
CDS_LIB"mstr_standard"
BODY_TYPE"PLUMBING"
HDL_TAP"TRUE";
"B \NAC \NWC"1;
"S \NAC"
BN"4"80;
%"TAP"
"1","(-2925,2450)","0","mstr_standard","I61";
;
CDS_LIB"mstr_standard"
BODY_TYPE"PLUMBING"
HDL_TAP"TRUE";
"B \NAC \NWC"1;
"S \NAC"
BN"2"82;
%"TAP"
"1","(-2925,2500)","0","mstr_standard","I62";
;
CDS_LIB"mstr_standard"
BODY_TYPE"PLUMBING"
HDL_TAP"TRUE";
"B \NAC \NWC"1;
"S \NAC"
BN"1"83;
%"TAP"
"1","(-2925,2550)","0","mstr_standard","I63";
;
CDS_LIB"mstr_standard"
BODY_TYPE"PLUMBING"
HDL_TAP"TRUE";
"B \NAC \NWC"1;
"S \NAC"
BN"0"84;
%"TAP"
"1","(-2925,2650)","0","mstr_standard","I64";
;
CDS_LIB"mstr_standard"
BODY_TYPE"PLUMBING"
HDL_TAP"TRUE";
"B \NAC \NWC"2;
"S \NAC"
BN"19"55;
%"TAP"
"1","(-2925,2750)","0","mstr_standard","I65";
;
CDS_LIB"mstr_standard"
BODY_TYPE"PLUMBING"
HDL_TAP"TRUE";
"B \NAC \NWC"2;
"S \NAC"
BN"17"57;
%"TAP"
"1","(-2925,2700)","0","mstr_standard","I66";
;
CDS_LIB"mstr_standard"
BODY_TYPE"PLUMBING"
HDL_TAP"TRUE";
"B \NAC \NWC"2;
"S \NAC"
BN"18"56;
%"TAP"
"1","(-2925,2800)","0","mstr_standard","I67";
;
CDS_LIB"mstr_standard"
BODY_TYPE"PLUMBING"
HDL_TAP"TRUE";
"B \NAC \NWC"2;
"S \NAC"
BN"16"58;
%"TAP"
"1","(-2925,2850)","0","mstr_standard","I68";
;
CDS_LIB"mstr_standard"
BODY_TYPE"PLUMBING"
HDL_TAP"TRUE";
"B \NAC \NWC"2;
"S \NAC"
BN"15"59;
%"TAP"
"1","(-2925,2900)","0","mstr_standard","I69";
;
CDS_LIB"mstr_standard"
BODY_TYPE"PLUMBING"
HDL_TAP"TRUE";
"B \NAC \NWC"2;
"S \NAC"
BN"14"60;
%"TAP"
"1","(-5250,1800)","2","mstr_standard","I7";
;
CDS_LIB"mstr_standard"
BODY_TYPE"PLUMBING"
HDL_TAP"TRUE";
"B \NAC \NWC"3;
"S \NAC"
BN"15"15;
%"TAP"
"1","(-2925,3000)","0","mstr_standard","I70";
;
CDS_LIB"mstr_standard"
BODY_TYPE"PLUMBING"
HDL_TAP"TRUE";
"B \NAC \NWC"2;
"S \NAC"
BN"12"62;
%"TAP"
"1","(-2925,2950)","0","mstr_standard","I71";
;
CDS_LIB"mstr_standard"
BODY_TYPE"PLUMBING"
HDL_TAP"TRUE";
"B \NAC \NWC"2;
"S \NAC"
BN"13"61;
%"TAP"
"1","(-2925,3050)","0","mstr_standard","I72";
;
CDS_LIB"mstr_standard"
BODY_TYPE"PLUMBING"
HDL_TAP"TRUE";
"B \NAC \NWC"2;
"S \NAC"
BN"11"63;
%"TAP"
"1","(-2925,3100)","0","mstr_standard","I73";
;
CDS_LIB"mstr_standard"
BODY_TYPE"PLUMBING"
HDL_TAP"TRUE";
"B \NAC \NWC"2;
"S \NAC"
BN"10"64;
%"TAP"
"1","(-2925,3150)","0","mstr_standard","I74";
;
CDS_LIB"mstr_standard"
BODY_TYPE"PLUMBING"
HDL_TAP"TRUE";
"B \NAC \NWC"2;
"S \NAC"
BN"9"65;
%"TAP"
"1","(-2925,3250)","0","mstr_standard","I75";
;
CDS_LIB"mstr_standard"
BODY_TYPE"PLUMBING"
HDL_TAP"TRUE";
"B \NAC \NWC"2;
"S \NAC"
BN"7"5;
%"TAP"
"1","(-2925,3300)","0","mstr_standard","I76";
;
CDS_LIB"mstr_standard"
BODY_TYPE"PLUMBING"
HDL_TAP"TRUE";
"B \NAC \NWC"2;
"S \NAC"
BN"6"67;
%"TAP"
"1","(-2925,3200)","0","mstr_standard","I77";
;
CDS_LIB"mstr_standard"
BODY_TYPE"PLUMBING"
HDL_TAP"TRUE";
"B \NAC \NWC"2;
"S \NAC"
BN"8"66;
%"TAP"
"1","(-2925,3350)","0","mstr_standard","I78";
;
CDS_LIB"mstr_standard"
BODY_TYPE"PLUMBING"
HDL_TAP"TRUE";
"B \NAC \NWC"2;
"S \NAC"
BN"5"68;
%"TAP"
"1","(-2925,3400)","0","mstr_standard","I79";
;
CDS_LIB"mstr_standard"
BODY_TYPE"PLUMBING"
HDL_TAP"TRUE";
"B \NAC \NWC"2;
"S \NAC"
BN"4"69;
%"TAP"
"1","(-5250,1850)","2","mstr_standard","I8";
;
CDS_LIB"mstr_standard"
BODY_TYPE"PLUMBING"
HDL_TAP"TRUE";
"B \NAC \NWC"3;
"S \NAC"
BN"14"16;
%"TAP"
"1","(-2925,3550)","0","mstr_standard","I80";
;
CDS_LIB"mstr_standard"
BODY_TYPE"PLUMBING"
HDL_TAP"TRUE";
"B \NAC \NWC"2;
"S \NAC"
BN"1"72;
%"TAP"
"1","(-2925,3500)","0","mstr_standard","I81";
;
CDS_LIB"mstr_standard"
BODY_TYPE"PLUMBING"
HDL_TAP"TRUE";
"B \NAC \NWC"2;
"S \NAC"
BN"2"71;
%"TAP"
"1","(-2925,3450)","0","mstr_standard","I82";
;
CDS_LIB"mstr_standard"
BODY_TYPE"PLUMBING"
HDL_TAP"TRUE";
"B \NAC \NWC"2;
"S \NAC"
BN"3"70;
%"TAP"
"1","(-2925,3600)","0","mstr_standard","I83";
;
CDS_LIB"mstr_standard"
BODY_TYPE"PLUMBING"
HDL_TAP"TRUE";
"B \NAC \NWC"2;
"S \NAC"
BN"0"73;
%"SKX_EXT_B"
"13","(-4075,2600)","0","chpset_lib","I86";
;
CDS_SEC"13"
PART_NUMBER"TBD"
MATERIAL"IC"
LOCATION"U5D1"
PACK_TYPE"BGA1"
CDS_LIB"chpset_lib"
SEC_TYPE"BGA1"
SEC"13"
CDS_LOCATION"U5D1"
ROOM"CPU0";
"UPI0_TX_DP<0>"
$PN"M1"55;
"UPI0_TX_DP<1>"
$PN"T1"56;
"UPI0_TX_DP<2>"
$PN"Y3"57;
"UPI0_TX_DP<3>"
$PN"W2"58;
"UPI0_TX_DP<4>"
$PN"AA2"59;
"UPI0_TX_DP<5>"
$PN"AD1"60;
"UPI0_TX_DP<6>"
$PN"AF3"61;
"UPI0_TX_DP<7>"
$PN"AG2"62;
"UPI0_TX_DP<8>"
$PN"AJ2"63;
"UPI0_TX_DP<9>"
$PN"AK1"64;
"UPI0_TX_DP<10>"
$PN"AK3"65;
"UPI0_TX_DP<11>"
$PN"AP3"66;
"UPI0_TX_DP<12>"
$PN"AP1"5;
"UPI0_TX_DP<13>"
$PN"AR2"67;
"UPI0_TX_DP<14>"
$PN"AR4"68;
"UPI0_TX_DP<15>"
$PN"AW4"69;
"UPI0_TX_DP<16>"
$PN"AY3"70;
"UPI0_TX_DP<17>"
$PN"BC2"71;
"UPI0_TX_DP<18>"
$PN"BD3"72;
"UPI0_TX_DP<19>"
$PN"BH3"73;
"UPI0_TX_DN<0>"
$PN"N2"46;
"UPI0_TX_DN<1>"
$PN"P1"47;
"UPI0_TX_DN<2>"
$PN"V3"48;
"UPI0_TX_DN<3>"
$PN"Y1"49;
"UPI0_TX_DN<4>"
$PN"AB3"50;
"UPI0_TX_DN<5>"
$PN"AC2"51;
"UPI0_TX_DN<6>"
$PN"AG4"52;
"UPI0_TX_DN<7>"
$PN"AE2"53;
"UPI0_TX_DN<8>"
$PN"AH3"54;
"UPI0_TX_DN<9>"
$PN"AL2"74;
"UPI0_TX_DN<10>"
$PN"AM3"75;
"UPI0_TX_DN<11>"
$PN"AN4"76;
"UPI0_TX_DN<12>"
$PN"AT1"77;
"UPI0_TX_DN<13>"
$PN"AT3"78;
"UPI0_TX_DN<14>"
$PN"AU4"79;
"UPI0_TX_DN<15>"
$PN"AV5"80;
"UPI0_TX_DN<16>"
$PN"BA4"81;
"UPI0_TX_DN<17>"
$PN"BB3"82;
"UPI0_TX_DN<18>"
$PN"BF3"83;
"UPI0_TX_DN<19>"
$PN"BG4"84;
"UPI0_RX_DP<0>"
$PN"AB9"20;
"UPI0_RX_DP<1>"
$PN"AC8"21;
"UPI0_RX_DP<2>"
$PN"AA6"22;
"UPI0_RX_DP<3>"
$PN"AC6"23;
"UPI0_RX_DP<4>"
$PN"AG6"24;
"UPI0_RX_DP<5>"
$PN"AF7"6;
"UPI0_RX_DP<6>"
$PN"AH7"10;
"UPI0_RX_DP<7>"
$PN"AK5"7;
"UPI0_RX_DP<8>"
$PN"AM7"25;
"UPI0_RX_DP<9>"
$PN"AL8"9;
"UPI0_RX_DP<10>"
$PN"AN8"8;
"UPI0_RX_DP<11>"
$PN"AU8"26;
"UPI0_RX_DP<12>"
$PN"AT9"27;
"UPI0_RX_DP<13>"
$PN"AY7"28;
"UPI0_RX_DP<14>"
$PN"BB7"29;
"UPI0_RX_DP<15>"
$PN"BF7"30;
"UPI0_RX_DP<16>"
$PN"AV9"31;
"UPI0_RX_DP<17>"
$PN"BB9"32;
"UPI0_RX_DP<18>"
$PN"BC10"33;
"UPI0_RX_DP<19>"
$PN"BA10"34;
"UPI0_RX_DN<0>"
$PN"AC10"11;
"UPI0_RX_DN<1>"
$PN"AA8"12;
"UPI0_RX_DN<2>"
$PN"AB7"13;
"UPI0_RX_DN<3>"
$PN"AD5"14;
"UPI0_RX_DN<4>"
$PN"AE6"15;
"UPI0_RX_DN<5>"
$PN"AG8"16;
"UPI0_RX_DN<6>"
$PN"AJ6"17;
"UPI0_RX_DN<7>"
$PN"AL6"18;
"UPI0_RX_DN<8>"
$PN"AK7"19;
"UPI0_RX_DN<9>"
$PN"AM9"35;
"UPI0_RX_DN<10>"
$PN"AP7"36;
"UPI0_RX_DN<11>"
$PN"AR8"37;
"UPI0_RX_DN<12>"
$PN"AU10"38;
"UPI0_RX_DN<13>"
$PN"BA8"39;
"UPI0_RX_DN<14>"
$PN"BC6"40;
"UPI0_RX_DN<15>"
$PN"BD7"41;
"UPI0_RX_DN<16>"
$PN"AW8"42;
"UPI0_RX_DN<17>"
$PN"AY9"43;
"UPI0_RX_DN<18>"
$PN"BD9"44;
"UPI0_RX_DN<19>"
$PN"BB11"45;
%"TAP"
"1","(-5250,1950)","2","mstr_standard","I9";
;
CDS_LIB"mstr_standard"
BODY_TYPE"PLUMBING"
HDL_TAP"TRUE";
"B \NAC \NWC"3;
"S \NAC"
BN"12"18;
END.
